# T6G (Grand Teton) — schematic netlist excerpt (pin names and nets, part order shuffled) for the footprints in the layout excerpt that follows; sources: Cadence DE-HDL packaged netlist, KiCad conversion of 04192023_DAF0TMB3IC0_F0TG_MB_C_brd_V02_OCP.brd

R547  Q_RES  4.7K 5% CHIP  pkg 0402LF  page 55 : A = FM_CPU1_BMC_RST_N ; B = PVDD18_S5_P1
C2449  Q_CAP  22UF 4V 20% X6S  pkg C0402  page 74 : A = PVDDCR_SOC_P1 ; B = GND

(kicad_pcb
	(version 20260206)
	(generator "pcbnew")
	(generator_version "10.0")
	(general
		(thickness 1.6)
		(legacy_teardrops no)
	)
	(paper "A4")
	(title_block
		(title "04192023_DAF0TMB3IC0_F0TG_MB_C_brd_V02_OCP.brd")
		(comment 1 "Grand Teton / footprints 6142-6143 of 8354")
	)
	(layers
		(0 "F.Cu" signal "TOP")
		(4 "In1.Cu" signal "GND")
		(6 "In2.Cu" signal "IN1")
		(8 "In3.Cu" signal "GND1")
		(10 "In4.Cu" signal "IN2")
		(12 "In5.Cu" signal "GND2")
		(14 "In6.Cu" signal "IN3")
		(16 "In7.Cu" signal "GND3")
		(18 "In8.Cu" signal "VCC")
		(20 "In9.Cu" signal "VCC1")
		(22 "In10.Cu" signal "GND4")
		(24 "In11.Cu" signal "IN4")
		(26 "In12.Cu" signal "GND5")
		(28 "In13.Cu" signal "IN5")
		(30 "In14.Cu" signal "GND6")
		(32 "In15.Cu" signal "IN6")
		(34 "In16.Cu" signal "GND7")
		(2 "B.Cu" signal "BOTTOM")
		(9 "F.Adhes" user "F.Adhesive")
		(11 "B.Adhes" user "B.Adhesive")
		(13 "F.Paste" user "Package Geometry/Pastemask Top")
		(15 "B.Paste" user "Package Geometry/Pastemask Bottom")
		(5 "F.SilkS" user "Ref Des/Silkscreen Top")
		(7 "B.SilkS" user "Ref Des/Silkscreen Bottom")
		(1 "F.Mask" user "Board Geometry/Soldermask Top")
		(3 "B.Mask" user "Board Geometry/Soldermask Bottom")
		(17 "Dwgs.User" user "User.Drawings")
		(19 "Cmts.User" user "User.Comments")
		(21 "Eco1.User" user "User.Eco1")
		(23 "Eco2.User" user "User.Eco2")
		(25 "Edge.Cuts" user "Board Geometry/Outline")
		(27 "Margin" user)
		(31 "F.CrtYd" user "Package Geometry/Place Bound Top")
		(29 "B.CrtYd" user "Package Geometry/Place Bound Bottom")
		(35 "F.Fab" user "Ref Des/Assembly Top")
		(33 "B.Fab" user "Ref Des/Assembly Bottom")
	)
	(footprint ""
		(layer "B.Cu")
		(at 144.932654 -315.49467 180)
		(property "Reference" "R547"
			(at 0 0 0)
			(layer "B.SilkS")
			(hide yes)
			(effects
				(font
					(size 1.27 1.27)
				)
				(justify mirror)
			)
		)
		(property "Value" ""
			(at 0 0 0)
			(layer "B.Fab")
			(effects
				(font
					(size 1.27 1.27)
				)
				(justify mirror)
			)
		)
		(duplicate_pad_numbers_are_jumpers no)
		(fp_line
			(start 0.7874 0.4064)
			(end 0.7874 -0.4064)
			(stroke
				(width 0.1524)
				(type default)
			)
			(layer "B.SilkS")
		)
		(fp_line
			(start 0.7874 -0.4064)
			(end -0.7874 -0.4064)
			(stroke
				(width 0.1524)
				(type default)
			)
			(layer "B.SilkS")
		)
		(fp_line
			(start -0.7874 0.4064)
			(end 0.7874 0.4064)
			(stroke
				(width 0.1524)
				(type default)
			)
			(layer "B.SilkS")
		)
		(fp_line
			(start -0.7874 -0.4064)
			(end -0.7874 0.4064)
			(stroke
				(width 0.1524)
				(type default)
			)
			(layer "B.SilkS")
		)
		(fp_line
			(start 0.67945 0.3048)
			(end 0.67945 -0.305054)
			(stroke
				(width 0.1)
				(type default)
			)
			(layer "B.Fab")
		)
		(fp_line
			(start 0.67945 -0.305054)
			(end 0.12065 -0.305054)
			(stroke
				(width 0.1)
				(type default)
			)
			(layer "B.Fab")
		)
		(fp_line
			(start 0.12065 0.3048)
			(end 0.67945 0.3048)
			(stroke
				(width 0.1)
				(type default)
			)
			(layer "B.Fab")
		)
		(fp_line
			(start 0.12065 0.2794)
			(end 0.12065 0.3048)
			(stroke
				(width 0.1)
				(type default)
			)
			(layer "B.Fab")
		)
		(fp_line
			(start 0.12065 -0.2794)
			(end -0.12065 -0.2794)
			(stroke
				(width 0.1)
				(type default)
			)
			(layer "B.Fab")
		)
		(fp_line
			(start 0.12065 -0.305054)
			(end 0.12065 -0.2794)
			(stroke
				(width 0.1)
				(type default)
			)
			(layer "B.Fab")
		)
		(fp_line
			(start -0.120396 0.3048)
			(end -0.120396 0.2794)
			(stroke
				(width 0.1)
				(type default)
			)
			(layer "B.Fab")
		)
		(fp_line
			(start -0.120396 0.2794)
			(end 0.12065 0.2794)
			(stroke
				(width 0.1)
				(type default)
			)
			(layer "B.Fab")
		)
		(fp_line
			(start -0.12065 -0.2794)
			(end -0.12065 -0.3048)
			(stroke
				(width 0.1)
				(type default)
			)
			(layer "B.Fab")
		)
		(fp_line
			(start -0.12065 -0.3048)
			(end -0.67945 -0.3048)
			(stroke
				(width 0.1)
				(type default)
			)
			(layer "B.Fab")
		)
		(fp_line
			(start -0.67945 0.3048)
			(end -0.120396 0.3048)
			(stroke
				(width 0.1)
				(type default)
			)
			(layer "B.Fab")
		)
		(fp_line
			(start -0.67945 -0.3048)
			(end -0.67945 0.3048)
			(stroke
				(width 0.1)
				(type default)
			)
			(layer "B.Fab")
		)
		(pad "1" smd circle
			(at 0.40005 0)
			(size 0 0)
			(layers "B.Cu" "B.Mask" "B.Paste")
			(net "FM_CPU1_BMC_RST_N")
		)
		(pad "2" smd circle
			(at -0.40005 0)
			(size 0 0)
			(layers "B.Cu" "B.Mask" "B.Paste")
			(net "PVDD18_S5_P1")
		)
	)
	(footprint ""
		(layer "B.Cu")
		(at 121.706386 -250.892564)
		(property "Reference" "C2449"
			(at 0 0 0)
			(layer "B.SilkS")
			(hide yes)
			(effects
				(font
					(size 1.27 1.27)
				)
				(justify mirror)
			)
		)
		(property "Value" ""
			(at 0 0 0)
			(layer "B.Fab")
			(effects
				(font
					(size 1.27 1.27)
				)
				(justify mirror)
			)
		)
		(duplicate_pad_numbers_are_jumpers no)
		(fp_line
			(start -0.7874 -0.4064)
			(end -0.7874 0.4064)
			(stroke
				(width 0.1524)
				(type default)
			)
			(layer "B.SilkS")
		)
		(fp_line
			(start -0.7874 0.4064)
			(end 0.7874 0.4064)
			(stroke
				(width 0.1524)
				(type default)
			)
			(layer "B.SilkS")
		)
		(fp_line
			(start 0.7874 -0.4064)
			(end -0.7874 -0.4064)
			(stroke
				(width 0.1524)
				(type default)
			)
			(layer "B.SilkS")
		)
		(fp_line
			(start 0.7874 0.4064)
			(end 0.7874 -0.4064)
			(stroke
				(width 0.1524)
				(type default)
			)
			(layer "B.SilkS")
		)
		(fp_line
			(start -0.67945 -0.3048)
			(end -0.67945 0.3048)
			(stroke
				(width 0.1)
				(type default)
			)
			(layer "B.Fab")
		)
		(fp_line
			(start -0.67945 0.3048)
			(end -0.120396 0.3048)
			(stroke
				(width 0.1)
				(type default)
			)
			(layer "B.Fab")
		)
		(fp_line
			(start -0.12065 -0.3048)
			(end -0.67945 -0.3048)
			(stroke
				(width 0.1)
				(type default)
			)
			(layer "B.Fab")
		)
		(fp_line
			(start -0.12065 -0.2794)
			(end -0.12065 -0.3048)
			(stroke
				(width 0.1)
				(type default)
			)
			(layer "B.Fab")
		)
		(fp_line
			(start -0.120396 0.2794)
			(end 0.12065 0.2794)
			(stroke
				(width 0.1)
				(type default)
			)
			(layer "B.Fab")
		)
		(fp_line
			(start -0.120396 0.3048)
			(end -0.120396 0.2794)
			(stroke
				(width 0.1)
				(type default)
			)
			(layer "B.Fab")
		)
		(fp_line
			(start 0.12065 -0.305054)
			(end 0.12065 -0.2794)
			(stroke
				(width 0.1)
				(type default)
			)
			(layer "B.Fab")
		)
		(fp_line
			(start 0.12065 -0.2794)
			(end -0.12065 -0.2794)
			(stroke
				(width 0.1)
				(type default)
			)
			(layer "B.Fab")
		)
		(fp_line
			(start 0.12065 0.2794)
			(end 0.12065 0.3048)
			(stroke
				(width 0.1)
				(type default)
			)
			(layer "B.Fab")
		)
		(fp_line
			(start 0.12065 0.3048)
			(end 0.67945 0.3048)
			(stroke
				(width 0.1)
				(type default)
			)
			(layer "B.Fab")
		)
		(fp_line
			(start 0.67945 -0.305054)
			(end 0.12065 -0.305054)
			(stroke
				(width 0.1)
				(type default)
			)
			(layer "B.Fab")
		)
		(fp_line
			(start 0.67945 0.3048)
			(end 0.67945 -0.305054)
			(stroke
				(width 0.1)
				(type default)
			)
			(layer "B.Fab")
		)
		(pad "1" smd circle
			(at 0.40005 0 180)
			(size 0 0)
			(layers "B.Cu" "B.Mask" "B.Paste")
			(net "PVDDCR_SOC_P1")
		)
		(pad "2" smd circle
			(at -0.40005 0 180)
			(size 0 0)
			(layers "B.Cu" "B.Mask" "B.Paste")
			(net "GND")
		)
	)
)
